# S9S_MB_2U (Grand Teton) — schematic netlist excerpt (pin names and nets, part order shuffled) for the footprints in the layout excerpt that follows; sources: Cadence DE-HDL packaged netlist, KiCad conversion of 03242023_DA0F0TMBIJ0_F0T_Motherboard_J_brd_V01_OCP.brd

C1934  Q_CAP  0.01UF 50V 10% X7R  pkg C0402  page 217 : A = VCC_PLD_CORE ; B = GND
PC457_P1_1  Q_CAP  22UF 4V 20% X6S  pkg C0805  page 293 : A = PVCCINFAON_CPU1 ; B = GND
R1241  Q_RES  249 1% CHIP  pkg 0402LF  page 117 : A = H_PMAX_TRIGGER_IO_CPU0 ; B = GND

(kicad_pcb
	(version 20260206)
	(generator "pcbnew")
	(generator_version "10.0")
	(general
		(thickness 1.6)
		(legacy_teardrops no)
	)
	(paper "A4")
	(title_block
		(title "03242023_DA0F0TMBIJ0_F0T_Motherboard_J_brd_V01_OCP.brd")
		(comment 1 "Grand Teton / footprints 4652-4654 of 6105")
	)
	(layers
		(0 "F.Cu" signal "TOP")
		(4 "In1.Cu" signal "GND")
		(6 "In2.Cu" signal "IN1")
		(8 "In3.Cu" signal "GND1")
		(10 "In4.Cu" signal "IN2")
		(12 "In5.Cu" signal "GND2")
		(14 "In6.Cu" signal "IN3")
		(16 "In7.Cu" signal "GND3")
		(18 "In8.Cu" signal "VCC")
		(20 "In9.Cu" signal "VCC1")
		(22 "In10.Cu" signal "GND4")
		(24 "In11.Cu" signal "IN4")
		(26 "In12.Cu" signal "GND5")
		(28 "In13.Cu" signal "IN5")
		(30 "In14.Cu" signal "GND6")
		(32 "In15.Cu" signal "IN6")
		(34 "In16.Cu" signal "GND7")
		(2 "B.Cu" signal "BOTTOM")
		(9 "F.Adhes" user "F.Adhesive")
		(11 "B.Adhes" user "B.Adhesive")
		(13 "F.Paste" user "Package Geometry/Pastemask Top")
		(15 "B.Paste" user "Package Geometry/Pastemask Bottom")
		(5 "F.SilkS" user "Ref Des/Silkscreen Top")
		(7 "B.SilkS" user "Ref Des/Silkscreen Bottom")
		(1 "F.Mask" user "Board Geometry/Soldermask Top")
		(3 "B.Mask" user "Board Geometry/Soldermask Bottom")
		(17 "Dwgs.User" user "User.Drawings")
		(19 "Cmts.User" user "User.Comments")
		(21 "Eco1.User" user "User.Eco1")
		(23 "Eco2.User" user "User.Eco2")
		(25 "Edge.Cuts" user "Board Geometry/Outline")
		(27 "Margin" user)
		(31 "F.CrtYd" user "Package Geometry/Place Bound Top")
		(29 "B.CrtYd" user "Package Geometry/Place Bound Bottom")
		(35 "F.Fab" user "Ref Des/Assembly Top")
		(33 "B.Fab" user "Ref Des/Assembly Bottom")
	)
	(footprint ""
		(layer "B.Cu")
		(at 315.284358 -230.50119)
		(property "Reference" "R1241"
			(at 0 0 0)
			(layer "B.SilkS")
			(hide yes)
			(effects
				(font
					(size 1.27 1.27)
				)
				(justify mirror)
			)
		)
		(property "Value" ""
			(at 0 0 0)
			(layer "B.Fab")
			(effects
				(font
					(size 1.27 1.27)
				)
				(justify mirror)
			)
		)
		(duplicate_pad_numbers_are_jumpers no)
		(fp_line
			(start -0.7874 -0.4064)
			(end -0.7874 0.4064)
			(stroke
				(width 0.1524)
				(type default)
			)
			(layer "B.SilkS")
		)
		(fp_line
			(start -0.7874 0.4064)
			(end 0.7874 0.4064)
			(stroke
				(width 0.1524)
				(type default)
			)
			(layer "B.SilkS")
		)
		(fp_line
			(start 0.7874 -0.4064)
			(end -0.7874 -0.4064)
			(stroke
				(width 0.1524)
				(type default)
			)
			(layer "B.SilkS")
		)
		(fp_line
			(start 0.7874 0.4064)
			(end 0.7874 -0.4064)
			(stroke
				(width 0.1524)
				(type default)
			)
			(layer "B.SilkS")
		)
		(fp_line
			(start -0.67945 -0.3048)
			(end -0.67945 0.3048)
			(stroke
				(width 0.1)
				(type default)
			)
			(layer "B.Fab")
		)
		(fp_line
			(start -0.67945 0.3048)
			(end -0.120396 0.3048)
			(stroke
				(width 0.1)
				(type default)
			)
			(layer "B.Fab")
		)
		(fp_line
			(start -0.12065 -0.3048)
			(end -0.67945 -0.3048)
			(stroke
				(width 0.1)
				(type default)
			)
			(layer "B.Fab")
		)
		(fp_line
			(start -0.12065 -0.2794)
			(end -0.12065 -0.3048)
			(stroke
				(width 0.1)
				(type default)
			)
			(layer "B.Fab")
		)
		(fp_line
			(start -0.120396 0.2794)
			(end 0.12065 0.2794)
			(stroke
				(width 0.1)
				(type default)
			)
			(layer "B.Fab")
		)
		(fp_line
			(start -0.120396 0.3048)
			(end -0.120396 0.2794)
			(stroke
				(width 0.1)
				(type default)
			)
			(layer "B.Fab")
		)
		(fp_line
			(start 0.12065 -0.305054)
			(end 0.12065 -0.2794)
			(stroke
				(width 0.1)
				(type default)
			)
			(layer "B.Fab")
		)
		(fp_line
			(start 0.12065 -0.2794)
			(end -0.12065 -0.2794)
			(stroke
				(width 0.1)
				(type default)
			)
			(layer "B.Fab")
		)
		(fp_line
			(start 0.12065 0.2794)
			(end 0.12065 0.3048)
			(stroke
				(width 0.1)
				(type default)
			)
			(layer "B.Fab")
		)
		(fp_line
			(start 0.12065 0.3048)
			(end 0.67945 0.3048)
			(stroke
				(width 0.1)
				(type default)
			)
			(layer "B.Fab")
		)
		(fp_line
			(start 0.67945 -0.305054)
			(end 0.12065 -0.305054)
			(stroke
				(width 0.1)
				(type default)
			)
			(layer "B.Fab")
		)
		(fp_line
			(start 0.67945 0.3048)
			(end 0.67945 -0.305054)
			(stroke
				(width 0.1)
				(type default)
			)
			(layer "B.Fab")
		)
		(pad "1" smd circle
			(at 0.40005 0 180)
			(size 0 0)
			(layers "B.Cu" "B.Mask" "B.Paste")
			(net "H_PMAX_TRIGGER_IO_CPU0")
		)
		(pad "2" smd circle
			(at -0.40005 0 180)
			(size 0 0)
			(layers "B.Cu" "B.Mask" "B.Paste")
			(net "GND")
		)
	)
	(footprint ""
		(layer "B.Cu")
		(at 62.996572 -159.87268)
		(property "Reference" "PC457_P1_1"
			(at 0 0 0)
			(layer "B.SilkS")
			(hide yes)
			(effects
				(font
					(size 1.27 1.27)
				)
				(justify mirror)
			)
		)
		(property "Value" ""
			(at 0 0 0)
			(layer "B.Fab")
			(effects
				(font
					(size 1.27 1.27)
				)
				(justify mirror)
			)
		)
		(duplicate_pad_numbers_are_jumpers no)
		(fp_line
			(start -1.524 -0.762)
			(end -1.524 0.762)
			(stroke
				(width 0.1524)
				(type default)
			)
			(layer "B.SilkS")
		)
		(fp_line
			(start -1.524 0.762)
			(end 1.524 0.762)
			(stroke
				(width 0.1524)
				(type default)
			)
			(layer "B.SilkS")
		)
		(fp_line
			(start 1.524 -0.762)
			(end -1.524 -0.762)
			(stroke
				(width 0.1524)
				(type default)
			)
			(layer "B.SilkS")
		)
		(fp_line
			(start 1.524 0.762)
			(end 1.524 -0.762)
			(stroke
				(width 0.1524)
				(type default)
			)
			(layer "B.SilkS")
		)
		(fp_line
			(start -1.1049 -0.724916)
			(end 1.1049 -0.724916)
			(stroke
				(width 0.1)
				(type default)
			)
			(layer "B.Fab")
		)
		(fp_line
			(start -1.1049 0.724916)
			(end -1.1049 -0.724916)
			(stroke
				(width 0.1)
				(type default)
			)
			(layer "B.Fab")
		)
		(fp_line
			(start 1.1049 -0.724916)
			(end 1.1049 0.724916)
			(stroke
				(width 0.1)
				(type default)
			)
			(layer "B.Fab")
		)
		(fp_line
			(start 1.1049 0.724916)
			(end -1.1049 0.724916)
			(stroke
				(width 0.1)
				(type default)
			)
			(layer "B.Fab")
		)
		(pad "1" smd rect
			(at 0.889 0)
			(size 1.016 1.27)
			(layers "B.Cu" "B.Mask" "B.Paste")
			(net "PVCCINFAON_CPU1")
		)
		(pad "2" smd rect
			(at -0.889 0)
			(size 1.016 1.27)
			(layers "B.Cu" "B.Mask" "B.Paste")
			(net "GND")
		)
	)
	(footprint ""
		(layer "B.Cu")
		(at 176.955704 -112.97539)
		(property "Reference" "C1934"
			(at 0 0 0)
			(layer "B.SilkS")
			(hide yes)
			(effects
				(font
					(size 1.27 1.27)
				)
				(justify mirror)
			)
		)
		(property "Value" ""
			(at 0 0 0)
			(layer "B.Fab")
			(effects
				(font
					(size 1.27 1.27)
				)
				(justify mirror)
			)
		)
		(duplicate_pad_numbers_are_jumpers no)
		(fp_line
			(start -0.69215 -0.2921)
			(end -0.69215 0.2921)
			(stroke
				(width 0.1524)
				(type default)
			)
			(layer "B.SilkS")
		)
		(fp_line
			(start -0.69215 0.2921)
			(end 0.69215 0.2921)
			(stroke
				(width 0.1524)
				(type default)
			)
			(layer "B.SilkS")
		)
		(fp_line
			(start 0.69215 -0.2921)
			(end -0.69215 -0.2921)
			(stroke
				(width 0.1524)
				(type default)
			)
			(layer "B.SilkS")
		)
		(fp_line
			(start 0.69215 0.2921)
			(end 0.69215 -0.2921)
			(stroke
				(width 0.1524)
				(type default)
			)
			(layer "B.SilkS")
		)
		(fp_line
			(start -0.51435 -0.2794)
			(end -0.51435 0.2794)
			(stroke
				(width 0.1)
				(type default)
			)
			(layer "B.Fab")
		)
		(fp_line
			(start -0.51435 0.2794)
			(end 0.51435 0.2794)
			(stroke
				(width 0.1)
				(type default)
			)
			(layer "B.Fab")
		)
		(fp_line
			(start 0.51435 -0.2794)
			(end -0.51435 -0.2794)
			(stroke
				(width 0.1)
				(type default)
			)
			(layer "B.Fab")
		)
		(fp_line
			(start 0.51435 0.2794)
			(end 0.51435 -0.2794)
			(stroke
				(width 0.1)
				(type default)
			)
			(layer "B.Fab")
		)
		(pad "1" smd circle
			(at 0.40005 0 180)
			(size 0 0)
			(layers "B.Cu" "B.Mask" "B.Paste")
			(net "VCC_PLD_CORE")
		)
		(pad "2" smd circle
			(at -0.40005 0 180)
			(size 0 0)
			(layers "B.Cu" "B.Mask" "B.Paste")
			(net "GND")
		)
		(zone
			(layer "B.Cu")
			(hatch none 0.5)
			(connect_pads
				(clearance 0)
			)
			(min_thickness 0.25)
			(keepout
				(tracks not_allowed)
				(vias allowed)
				(pads allowed)
				(copperpour not_allowed)
				(footprints allowed)
			)
			(placement
				(enabled no)
				(sheetname "")
			)
			(fill
				(thermal_gap 0.5)
				(thermal_bridge_width 0.5)
				(island_removal_mode 0)
			)
			(polygon
				(pts
					(xy 177.146204 -112.88776) (xy 177.054764 -112.829594) (xy 176.855374 -112.829594) (xy 176.765204 -112.88776)
					(xy 176.765204 -113.06302) (xy 176.855374 -113.12144) (xy 177.054764 -113.12144) (xy 177.146204 -113.063274)
				)
			)
		)
	)
)
